(kicad_pcb
	(version 20260206)
	(generator "pcbnew")
	(generator_version "10.0")
	(general
		(thickness 1.6)
		(legacy_teardrops no)
	)
	(paper "A4")
	(title_block
		(title "Bryce Canyon_IOM_IOC_16318-2_OCP.brd")
		(comment 1 "Bryce Canyon / footprints 145-150 of 1605")
	)
	(layers
		(0 "F.Cu" signal "TOP")
		(4 "In1.Cu" signal "L2GND")
		(6 "In2.Cu" signal "L3")
		(8 "In3.Cu" signal "L4VCC")
		(10 "In4.Cu" signal "L5VCC")
		(12 "In5.Cu" signal "L6")
		(14 "In6.Cu" signal "L7GND")
		(2 "B.Cu" signal "BOTTOM")
		(9 "F.Adhes" user "F.Adhesive")
		(11 "B.Adhes" user "B.Adhesive")
		(13 "F.Paste" user "Package Geometry/Pastemask Top")
		(15 "B.Paste" user "Package Geometry/Pastemask Bottom")
		(5 "F.SilkS" user "Ref Des/Silkscreen Top")
		(7 "B.SilkS" user "Ref Des/Silkscreen Bottom")
		(1 "F.Mask" user "Board Geometry/Soldermask Top")
		(3 "B.Mask" user "Board Geometry/Soldermask Bottom")
		(17 "Dwgs.User" user "User.Drawings")
		(19 "Cmts.User" user "User.Comments")
		(21 "Eco1.User" user "User.Eco1")
		(23 "Eco2.User" user "User.Eco2")
		(25 "Edge.Cuts" user "Board Geometry/Outline")
		(27 "Margin" user)
		(31 "F.CrtYd" user "Package Geometry/Place Bound Top")
		(29 "B.CrtYd" user "Package Geometry/Place Bound Bottom")
		(35 "F.Fab" user "Ref Des/Assembly Top")
		(33 "B.Fab" user "Ref Des/Assembly Bottom")
	)
	(footprint ""
		(layer "F.Cu")
		(at 164.179758 -104.022398)
		(property "Reference" "LED5"
			(at 0 0 0)
			(layer "F.SilkS")
			(hide yes)
			(effects
				(font
					(size 1.27 1.27)
				)
			)
		)
		(property "Value" "LED-YG-51-GP"
			(at -2.6924 -1.4224 0)
			(unlocked yes)
			(layer "F.Fab")
			(hide yes)
			(effects
				(font
					(size 1.016 1.016)
					(thickness 0.1524)
				)
			)
		)
		(property "Device Type" "LED1608AKH40"
			(at -2.6924 -2.9464 0)
			(unlocked yes)
			(layer "F.Fab")
			(hide yes)
			(effects
				(font
					(size 1.016 1.016)
					(thickness 0.1524)
				)
			)
		)
		(duplicate_pad_numbers_are_jumpers no)
		(fp_line
			(start -0.7493 1.651)
			(end -0.7493 1.1811)
			(stroke
				(width 0.3302)
				(type default)
			)
			(layer "F.SilkS")
		)
		(fp_line
			(start -0.6604 -1.3716)
			(end 0.6604 -1.3716)
			(stroke
				(width 0.1524)
				(type default)
			)
			(layer "F.SilkS")
		)
		(fp_line
			(start -0.6604 1.3716)
			(end -0.6604 -1.3716)
			(stroke
				(width 0.1524)
				(type default)
			)
			(layer "F.SilkS")
		)
		(fp_line
			(start -0.5969 1.5494)
			(end 0.5842 1.5494)
			(stroke
				(width 0.508)
				(type default)
			)
			(layer "F.SilkS")
		)
		(fp_line
			(start 0.6604 -1.3716)
			(end 0.6604 1.3716)
			(stroke
				(width 0.1524)
				(type default)
			)
			(layer "F.SilkS")
		)
		(fp_line
			(start 0.6604 1.3716)
			(end -0.6604 1.3716)
			(stroke
				(width 0.1524)
				(type default)
			)
			(layer "F.SilkS")
		)
		(fp_line
			(start 0.7493 1.651)
			(end 0.7493 1.1811)
			(stroke
				(width 0.3302)
				(type default)
			)
			(layer "F.SilkS")
		)
		(fp_rect
			(start -0.6223 1.3335)
			(end 0.6223 -1.3335)
			(stroke
				(width 0)
				(type default)
			)
			(fill no)
			(layer "F.CrtYd")
		)
		(fp_rect
			(start -0.6223 1.3335)
			(end 0.6223 -1.3335)
			(stroke
				(width 0)
				(type default)
			)
			(fill no)
			(layer "F.Fab")
		)
		(pad "A" smd custom
			(at 0 -0.762)
			(size 0.2159 0.2159)
			(layers "F.Cu" "F.Mask" "F.Paste")
			(net "SYS_HB_LED_R")
			(options
				(clearance outline)
				(anchor circle)
			)
			(primitives
				(gr_poly
					(pts
						(arc
							(start -0.3302 -0.4318)
							(mid -0.402042 -0.402042)
							(end -0.4318 -0.3302)
						)
						(arc
							(start -0.4318 0.3302)
							(mid -0.402042 0.402042)
							(end -0.3302 0.4318)
						)
						(arc
							(start 0.3302 0.4318)
							(mid 0.402042 0.402042)
							(end 0.4318 0.3302)
						)
						(arc
							(start 0.4318 -0.3302)
							(mid 0.402042 -0.402042)
							(end 0.3302 -0.4318)
						)
					)
					(width 0)
					(fill yes)
				)
			)
		)
		(pad "K" smd custom
			(at 0 0.762)
			(size 0.2159 0.2159)
			(layers "F.Cu" "F.Mask" "F.Paste")
			(net "SYS_HB_LED_D")
			(options
				(clearance outline)
				(anchor circle)
			)
			(primitives
				(gr_poly
					(pts
						(arc
							(start -0.3302 -0.4318)
							(mid -0.402042 -0.402042)
							(end -0.4318 -0.3302)
						)
						(arc
							(start -0.4318 0.3302)
							(mid -0.402042 0.402042)
							(end -0.3302 0.4318)
						)
						(arc
							(start 0.3302 0.4318)
							(mid 0.402042 0.402042)
							(end 0.4318 0.3302)
						)
						(arc
							(start 0.4318 -0.3302)
							(mid 0.402042 -0.402042)
							(end 0.3302 -0.4318)
						)
					)
					(width 0)
					(fill yes)
				)
			)
		)
	)
	(footprint ""
		(layer "F.Cu")
		(at 61.6966 -172.0596)
		(property "Reference" "R74"
			(at 0 0 0)
			(layer "F.SilkS")
			(hide yes)
			(effects
				(font
					(size 1.27 1.27)
				)
			)
		)
		(property "Value" "0R2J-2-GP"
			(at 0.064008 -3.993896 0)
			(unlocked yes)
			(layer "F.Fab")
			(hide yes)
			(effects
				(font
					(size 1.016 1.016)
					(thickness 0.1524)
				)
			)
		)
		(property "Device Type" "R402H16"
			(at 0.064008 -5.517896 0)
			(unlocked yes)
			(layer "F.Fab")
			(hide yes)
			(effects
				(font
					(size 1.016 1.016)
					(thickness 0.1524)
				)
			)
		)
		(duplicate_pad_numbers_are_jumpers no)
		(fp_line
			(start -0.508 -0.9398)
			(end -0.508 0.9398)
			(stroke
				(width 0.1524)
				(type default)
			)
			(layer "F.SilkS")
		)
		(fp_line
			(start 0.508 -0.9398)
			(end -0.508 -0.9398)
			(stroke
				(width 0.1524)
				(type default)
			)
			(layer "F.SilkS")
		)
		(fp_rect
			(start -0.508 0.9398)
			(end 0.508 -0.9398)
			(stroke
				(width 0)
				(type default)
			)
			(fill no)
			(layer "F.CrtYd")
		)
		(fp_rect
			(start -0.508 0.9398)
			(end 0.508 -0.9398)
			(stroke
				(width 0)
				(type default)
			)
			(fill no)
			(layer "F.Fab")
		)
		(pad "1" smd custom
			(at 0 -0.4445)
			(size 0.1397 0.1397)
			(layers "F.Cu" "F.Mask" "F.Paste")
			(net "FM_TPM_PRSNT_RST_N_C")
			(options
				(clearance outline)
				(anchor circle)
			)
			(primitives
				(gr_poly
					(pts
						(arc
							(start -0.1778 -0.2794)
							(mid -0.249642 -0.249642)
							(end -0.2794 -0.1778)
						)
						(arc
							(start -0.2794 0.1778)
							(mid -0.249642 0.249642)
							(end -0.1778 0.2794)
						)
						(arc
							(start 0.1778 0.2794)
							(mid 0.249642 0.249642)
							(end 0.2794 0.1778)
						)
						(arc
							(start 0.2794 -0.1778)
							(mid 0.249642 -0.249642)
							(end 0.1778 -0.2794)
						)
					)
					(width 0)
					(fill yes)
				)
			)
		)
		(pad "2" smd custom
			(at 0 0.4445)
			(size 0.1397 0.1397)
			(layers "F.Cu" "F.Mask" "F.Paste")
			(net "FM_TPM_PRSNT_RST_N")
			(options
				(clearance outline)
				(anchor circle)
			)
			(primitives
				(gr_poly
					(pts
						(arc
							(start -0.1778 -0.2794)
							(mid -0.249642 -0.249642)
							(end -0.2794 -0.1778)
						)
						(arc
							(start -0.2794 0.1778)
							(mid -0.249642 0.249642)
							(end -0.1778 0.2794)
						)
						(arc
							(start 0.1778 0.2794)
							(mid 0.249642 0.249642)
							(end 0.2794 0.1778)
						)
						(arc
							(start 0.2794 -0.1778)
							(mid 0.249642 -0.249642)
							(end 0.1778 -0.2794)
						)
					)
					(width 0)
					(fill yes)
				)
			)
		)
	)
	(footprint ""
		(layer "F.Cu")
		(at 48.5394 -131.6228 180)
		(property "Reference" "R178"
			(at 0 0 180)
			(layer "F.SilkS")
			(hide yes)
			(effects
				(font
					(size 1.27 1.27)
				)
			)
		)
		(property "Value" "0R2J-2-GP"
			(at 0.064008 -3.993896 180)
			(unlocked yes)
			(layer "F.Fab")
			(hide yes)
			(effects
				(font
					(size 1.016 1.016)
					(thickness 0.1524)
				)
			)
		)
		(property "Device Type" "R402H16"
			(at 0.064008 -5.517896 180)
			(unlocked yes)
			(layer "F.Fab")
			(hide yes)
			(effects
				(font
					(size 1.016 1.016)
					(thickness 0.1524)
				)
			)
		)
		(duplicate_pad_numbers_are_jumpers no)
		(fp_line
			(start 0.508 -0.9398)
			(end -0.508 -0.9398)
			(stroke
				(width 0.1524)
				(type default)
			)
			(layer "F.SilkS")
		)
		(fp_line
			(start -0.508 -0.9398)
			(end -0.508 0.9398)
			(stroke
				(width 0.1524)
				(type default)
			)
			(layer "F.SilkS")
		)
		(fp_rect
			(start -0.508 0.9398)
			(end 0.508 -0.9398)
			(stroke
				(width 0)
				(type default)
			)
			(fill no)
			(layer "F.CrtYd")
		)
		(fp_rect
			(start -0.508 0.9398)
			(end 0.508 -0.9398)
			(stroke
				(width 0)
				(type default)
			)
			(fill no)
			(layer "F.Fab")
		)
		(pad "1" smd custom
			(at 0 -0.4445 180)
			(size 0.1397 0.1397)
			(layers "F.Cu" "F.Mask" "F.Paste")
			(net "I2C_TPM_SDA")
			(options
				(clearance outline)
				(anchor circle)
			)
			(primitives
				(gr_poly
					(pts
						(arc
							(start -0.1778 -0.2794)
							(mid -0.249642 -0.249642)
							(end -0.2794 -0.1778)
						)
						(arc
							(start -0.2794 0.1778)
							(mid -0.249642 0.249642)
							(end -0.1778 0.2794)
						)
						(arc
							(start 0.1778 0.2794)
							(mid 0.249642 0.249642)
							(end 0.2794 0.1778)
						)
						(arc
							(start 0.2794 -0.1778)
							(mid 0.249642 -0.249642)
							(end 0.1778 -0.2794)
						)
					)
					(width 0)
					(fill yes)
				)
			)
		)
		(pad "2" smd custom
			(at 0 0.4445 180)
			(size 0.1397 0.1397)
			(layers "F.Cu" "F.Mask" "F.Paste")
			(net "BMC_SMB14_DAT")
			(options
				(clearance outline)
				(anchor circle)
			)
			(primitives
				(gr_poly
					(pts
						(arc
							(start -0.1778 -0.2794)
							(mid -0.249642 -0.249642)
							(end -0.2794 -0.1778)
						)
						(arc
							(start -0.2794 0.1778)
							(mid -0.249642 0.249642)
							(end -0.1778 0.2794)
						)
						(arc
							(start 0.1778 0.2794)
							(mid 0.249642 0.249642)
							(end 0.2794 0.1778)
						)
						(arc
							(start 0.2794 -0.1778)
							(mid 0.249642 -0.249642)
							(end 0.1778 -0.2794)
						)
					)
					(width 0)
					(fill yes)
				)
			)
		)
	)
	(footprint ""
		(layer "F.Cu")
		(at 90.02776 -123.83262)
		(property "Reference" "R725"
			(at 0 0 0)
			(layer "F.SilkS")
			(hide yes)
			(effects
				(font
					(size 1.27 1.27)
				)
			)
		)
		(property "Value" "4K7R2F-GP"
			(at 0.064008 -3.993896 0)
			(unlocked yes)
			(layer "F.Fab")
			(hide yes)
			(effects
				(font
					(size 1.016 1.016)
					(thickness 0.1524)
				)
			)
		)
		(property "Device Type" "R402H16"
			(at 0.064008 -5.517896 0)
			(unlocked yes)
			(layer "F.Fab")
			(hide yes)
			(effects
				(font
					(size 1.016 1.016)
					(thickness 0.1524)
				)
			)
		)
		(duplicate_pad_numbers_are_jumpers no)
		(fp_line
			(start -0.508 -0.9398)
			(end -0.508 0.9398)
			(stroke
				(width 0.1524)
				(type default)
			)
			(layer "F.SilkS")
		)
		(fp_line
			(start 0.508 -0.9398)
			(end -0.508 -0.9398)
			(stroke
				(width 0.1524)
				(type default)
			)
			(layer "F.SilkS")
		)
		(fp_rect
			(start -0.508 0.9398)
			(end 0.508 -0.9398)
			(stroke
				(width 0)
				(type default)
			)
			(fill no)
			(layer "F.CrtYd")
		)
		(fp_rect
			(start -0.508 0.9398)
			(end 0.508 -0.9398)
			(stroke
				(width 0)
				(type default)
			)
			(fill no)
			(layer "F.Fab")
		)
		(pad "1" smd custom
			(at 0 -0.4445)
			(size 0.1397 0.1397)
			(layers "F.Cu" "F.Mask" "F.Paste")
			(net "P3V3_STBY")
			(options
				(clearance outline)
				(anchor circle)
			)
			(primitives
				(gr_poly
					(pts
						(arc
							(start -0.1778 -0.2794)
							(mid -0.249642 -0.249642)
							(end -0.2794 -0.1778)
						)
						(arc
							(start -0.2794 0.1778)
							(mid -0.249642 0.249642)
							(end -0.1778 0.2794)
						)
						(arc
							(start 0.1778 0.2794)
							(mid 0.249642 0.249642)
							(end 0.2794 0.1778)
						)
						(arc
							(start 0.2794 -0.1778)
							(mid 0.249642 -0.249642)
							(end 0.1778 -0.2794)
						)
					)
					(width 0)
					(fill yes)
				)
			)
		)
		(pad "2" smd custom
			(at 0 0.4445)
			(size 0.1397 0.1397)
			(layers "F.Cu" "F.Mask" "F.Paste")
			(net "UART_COMP_IN_RX")
			(options
				(clearance outline)
				(anchor circle)
			)
			(primitives
				(gr_poly
					(pts
						(arc
							(start -0.1778 -0.2794)
							(mid -0.249642 -0.249642)
							(end -0.2794 -0.1778)
						)
						(arc
							(start -0.2794 0.1778)
							(mid -0.249642 0.249642)
							(end -0.1778 0.2794)
						)
						(arc
							(start 0.1778 0.2794)
							(mid 0.249642 0.249642)
							(end 0.2794 0.1778)
						)
						(arc
							(start 0.2794 -0.1778)
							(mid 0.249642 -0.249642)
							(end 0.1778 -0.2794)
						)
					)
					(width 0)
					(fill yes)
				)
			)
		)
	)
	(footprint ""
		(layer "F.Cu")
		(at 61.3918 -146.5326 -90)
		(property "Reference" "R166"
			(at 0 0 270)
			(layer "F.SilkS")
			(hide yes)
			(effects
				(font
					(size 1.27 1.27)
				)
			)
		)
		(property "Value" "0R2J-2-GP"
			(at 0.064008 -3.993896 270)
			(unlocked yes)
			(layer "F.Fab")
			(hide yes)
			(effects
				(font
					(size 1.016 1.016)
					(thickness 0.1524)
				)
			)
		)
		(property "Device Type" "R402H16"
			(at 0.064008 -5.517896 270)
			(unlocked yes)
			(layer "F.Fab")
			(hide yes)
			(effects
				(font
					(size 1.016 1.016)
					(thickness 0.1524)
				)
			)
		)
		(duplicate_pad_numbers_are_jumpers no)
		(fp_line
			(start -0.508 -0.9398)
			(end -0.508 0.9398)
			(stroke
				(width 0.1524)
				(type default)
			)
			(layer "F.SilkS")
		)
		(fp_line
			(start 0.508 -0.9398)
			(end -0.508 -0.9398)
			(stroke
				(width 0.1524)
				(type default)
			)
			(layer "F.SilkS")
		)
		(fp_rect
			(start -0.508 0.9398)
			(end 0.508 -0.9398)
			(stroke
				(width 0)
				(type default)
			)
			(fill no)
			(layer "F.CrtYd")
		)
		(fp_rect
			(start -0.508 0.9398)
			(end 0.508 -0.9398)
			(stroke
				(width 0)
				(type default)
			)
			(fill no)
			(layer "F.Fab")
		)
		(pad "1" smd custom
			(at 0 -0.4445 270)
			(size 0.1397 0.1397)
			(layers "F.Cu" "F.Mask" "F.Paste")
			(net "I2C_BMC_COMP_SDA_OUT")
			(options
				(clearance outline)
				(anchor circle)
			)
			(primitives
				(gr_poly
					(pts
						(arc
							(start -0.1778 -0.2794)
							(mid -0.249642 -0.249642)
							(end -0.2794 -0.1778)
						)
						(arc
							(start -0.2794 0.1778)
							(mid -0.249642 0.249642)
							(end -0.1778 0.2794)
						)
						(arc
							(start 0.1778 0.2794)
							(mid 0.249642 0.249642)
							(end 0.2794 0.1778)
						)
						(arc
							(start 0.2794 -0.1778)
							(mid 0.249642 -0.249642)
							(end 0.1778 -0.2794)
						)
					)
					(width 0)
					(fill yes)
				)
			)
		)
		(pad "2" smd custom
			(at 0 0.4445 270)
			(size 0.1397 0.1397)
			(layers "F.Cu" "F.Mask" "F.Paste")
			(net "BMC_SMB4_DAT")
			(options
				(clearance outline)
				(anchor circle)
			)
			(primitives
				(gr_poly
					(pts
						(arc
							(start -0.1778 -0.2794)
							(mid -0.249642 -0.249642)
							(end -0.2794 -0.1778)
						)
						(arc
							(start -0.2794 0.1778)
							(mid -0.249642 0.249642)
							(end -0.1778 0.2794)
						)
						(arc
							(start 0.1778 0.2794)
							(mid 0.249642 0.249642)
							(end 0.2794 0.1778)
						)
						(arc
							(start 0.2794 -0.1778)
							(mid 0.249642 -0.249642)
							(end 0.1778 -0.2794)
						)
					)
					(width 0)
					(fill yes)
				)
			)
		)
	)
	(footprint ""
		(layer "F.Cu")
		(at 193.7258 -13.72743)
		(property "Reference" "Q206"
			(at 0 0 0)
			(layer "F.SilkS")
			(hide yes)
			(effects
				(font
					(size 1.27 1.27)
				)
			)
		)
		(property "Value" "SSM6P39TU-GP"
			(at 0.0508 -11.5824 0)
			(unlocked yes)
			(layer "F.Fab")
			(hide yes)
			(effects
				(font
					(size 1.016 1.016)
					(thickness 0.1524)
				)
			)
		)
		(property "Device Type" "UMT6H30"
			(at 0.0508 -13.1572 0)
			(unlocked yes)
			(layer "F.Fab")
			(hide yes)
			(effects
				(font
					(size 1.016 1.016)
					(thickness 0.1524)
				)
			)
		)
		(duplicate_pad_numbers_are_jumpers no)
		(fp_line
			(start -1.27 -0.36449)
			(end -1.27 0.36449)
			(stroke
				(width 0.1524)
				(type default)
			)
			(layer "F.SilkS")
		)
		(fp_line
			(start -1.27 -0.36449)
			(end 1.524 -0.36449)
			(stroke
				(width 0.1524)
				(type default)
			)
			(layer "F.SilkS")
		)
		(fp_line
			(start 1.09347 0)
			(end 1.45796 0.36449)
			(stroke
				(width 0.1524)
				(type default)
			)
			(layer "F.SilkS")
		)
		(fp_line
			(start 1.45796 -0.36449)
			(end 1.09347 0)
			(stroke
				(width 0.1524)
				(type default)
			)
			(layer "F.SilkS")
		)
		(fp_line
			(start 1.524 -0.36449)
			(end 1.45796 -0.36449)
			(stroke
				(width 0.1524)
				(type default)
			)
			(layer "F.SilkS")
		)
		(fp_line
			(start 1.524 -0.36449)
			(end 1.524 -1.82245)
			(stroke
				(width 0.508)
				(type default)
			)
			(layer "F.SilkS")
		)
		(fp_line
			(start 1.524 -0.36449)
			(end 1.524 0.36449)
			(stroke
				(width 0.1524)
				(type default)
			)
			(layer "F.SilkS")
		)
		(fp_line
			(start 1.524 0.36449)
			(end -1.27 0.36449)
			(stroke
				(width 0.1524)
				(type default)
			)
			(layer "F.SilkS")
		)
		(fp_poly
			(pts
				(xy -0.65024 0.36449) (xy -0.65024 -0.36449) (xy 0.65024 -0.36449) (xy 0.65024 0.36449)
			)
			(stroke
				(width 0)
				(type default)
			)
			(fill yes)
			(layer "F.SilkS")
		)
		(fp_poly
			(pts
				(xy 1.016 -1.0668) (xy 1.016 1.0668) (xy -1.016 1.0668) (xy -1.016 -1.0668)
			)
			(stroke
				(width 0)
				(type default)
			)
			(fill no)
			(layer "F.CrtYd")
		)
		(fp_poly
			(pts
				(xy -1.524 1.905) (xy 1.524 1.905) (xy 1.524 -1.06426) (xy 1.016 -1.06426) (xy 1.016 1.0668) (xy -1.016 1.0668)
				(xy -1.016 -1.0668) (xy 1.524 -1.0668) (xy 1.524 -1.905) (xy -1.524 -1.905)
			)
			(stroke
				(width 0)
				(type default)
			)
			(fill no)
			(layer "F.CrtYd")
		)
		(fp_poly
			(pts
				(xy -1.524 -1.905) (xy -1.524 1.905) (xy 1.524 1.905) (xy 1.524 -1.905)
			)
			(stroke
				(width 0)
				(type default)
			)
			(fill no)
			(layer "F.Fab")
		)
		(pad "1" smd rect
			(at 0.65024 -1.02489)
			(size 0.4064 0.8128)
			(layers "F.Cu" "F.Mask" "F.Paste")
			(net "P3V3_STBY")
		)
		(pad "2" smd rect
			(at 0 -1.02489)
			(size 0.4064 0.8128)
			(layers "F.Cu" "F.Mask" "F.Paste")
			(net "EXT1_LED_YELLOW_G1")
		)
		(pad "3" smd rect
			(at -0.65024 -1.02489)
			(size 0.4064 0.8128)
			(layers "F.Cu" "F.Mask" "F.Paste")
			(net "EXT1_LED_BLUE_D")
		)
		(pad "4" smd rect
			(at -0.65024 1.02489)
			(size 0.4064 0.8128)
			(layers "F.Cu" "F.Mask" "F.Paste")
			(net "P5V_STBY")
		)
		(pad "5" smd rect
			(at 0 1.02489)
			(size 0.4064 0.8128)
			(layers "F.Cu" "F.Mask" "F.Paste")
			(net "EXT1_LED_BLUE_G2")
		)
		(pad "6" smd rect
			(at 0.65024 1.02489)
			(size 0.4064 0.8128)
			(layers "F.Cu" "F.Mask" "F.Paste")
			(net "EXT1_LED_YELLOW_D1")
		)
	)
)
